# S9S_MB_2U (Grand Teton) — schematic netlist excerpt (pin names and nets, part order shuffled) for the footprints in the layout excerpt that follows; sources: Cadence DE-HDL packaged netlist, KiCad conversion of 03242023_DA0F0TMBIJ0_F0T_Motherboard_J_brd_V01_OCP.brd

C287  Q_CAP  22UF 4V 20% X6S  pkg C0402  page 77 : A = PVCCIN_CPU1 ; B = GND
R4070  Q_RES  10K 1% CHIP  pkg 0402LF  page 156 : A = P12V_AUX ; B = P3V3_OCP_1_EN_G
C1528  Q_CAP_DIFFBUS  DIFF BUS_0.22UF 6.3V 20% X6S  pkg C0201  page 177 : \1\ = P5E_CPU1_PE3_TX_C_DN<9> ; \2\ = P5E_CPU1_PE3_TX_DN<9>

(kicad_pcb
	(version 20260206)
	(generator "pcbnew")
	(generator_version "10.0")
	(general
		(thickness 1.6)
		(legacy_teardrops no)
	)
	(paper "A4")
	(title_block
		(title "03242023_DA0F0TMBIJ0_F0T_Motherboard_J_brd_V01_OCP.brd")
		(comment 1 "Grand Teton / footprints 401-403 of 6105")
	)
	(layers
		(0 "F.Cu" signal "TOP")
		(4 "In1.Cu" signal "GND")
		(6 "In2.Cu" signal "IN1")
		(8 "In3.Cu" signal "GND1")
		(10 "In4.Cu" signal "IN2")
		(12 "In5.Cu" signal "GND2")
		(14 "In6.Cu" signal "IN3")
		(16 "In7.Cu" signal "GND3")
		(18 "In8.Cu" signal "VCC")
		(20 "In9.Cu" signal "VCC1")
		(22 "In10.Cu" signal "GND4")
		(24 "In11.Cu" signal "IN4")
		(26 "In12.Cu" signal "GND5")
		(28 "In13.Cu" signal "IN5")
		(30 "In14.Cu" signal "GND6")
		(32 "In15.Cu" signal "IN6")
		(34 "In16.Cu" signal "GND7")
		(2 "B.Cu" signal "BOTTOM")
		(9 "F.Adhes" user "F.Adhesive")
		(11 "B.Adhes" user "B.Adhesive")
		(13 "F.Paste" user "Package Geometry/Pastemask Top")
		(15 "B.Paste" user "Package Geometry/Pastemask Bottom")
		(5 "F.SilkS" user "Ref Des/Silkscreen Top")
		(7 "B.SilkS" user "Ref Des/Silkscreen Bottom")
		(1 "F.Mask" user "Board Geometry/Soldermask Top")
		(3 "B.Mask" user "Board Geometry/Soldermask Bottom")
		(17 "Dwgs.User" user "User.Drawings")
		(19 "Cmts.User" user "User.Comments")
		(21 "Eco1.User" user "User.Eco1")
		(23 "Eco2.User" user "User.Eco2")
		(25 "Edge.Cuts" user "Board Geometry/Outline")
		(27 "Margin" user)
		(31 "F.CrtYd" user "Package Geometry/Place Bound Top")
		(29 "B.CrtYd" user "Package Geometry/Place Bound Bottom")
		(35 "F.Fab" user "Ref Des/Assembly Top")
		(33 "B.Fab" user "Ref Des/Assembly Bottom")
	)
	(footprint ""
		(layer "F.Cu")
		(at 106.3244 -251.375672 90)
		(property "Reference" "C287"
			(at 0 0 90)
			(layer "F.SilkS")
			(hide yes)
			(effects
				(font
					(size 1.27 1.27)
				)
			)
		)
		(property "Value" ""
			(at 0 0 90)
			(layer "F.Fab")
			(effects
				(font
					(size 1.27 1.27)
				)
			)
		)
		(duplicate_pad_numbers_are_jumpers no)
		(fp_line
			(start 0.7874 -0.4064)
			(end 0.7874 0.4064)
			(stroke
				(width 0.1524)
				(type default)
			)
			(layer "F.SilkS")
		)
		(fp_line
			(start -0.7874 -0.4064)
			(end 0.7874 -0.4064)
			(stroke
				(width 0.1524)
				(type default)
			)
			(layer "F.SilkS")
		)
		(fp_line
			(start 0.7874 0.4064)
			(end -0.7874 0.4064)
			(stroke
				(width 0.1524)
				(type default)
			)
			(layer "F.SilkS")
		)
		(fp_line
			(start -0.7874 0.4064)
			(end -0.7874 -0.4064)
			(stroke
				(width 0.1524)
				(type default)
			)
			(layer "F.SilkS")
		)
		(fp_line
			(start -0.12065 -0.305054)
			(end -0.12065 -0.2794)
			(stroke
				(width 0.1)
				(type default)
			)
			(layer "F.Fab")
		)
		(fp_line
			(start -0.67945 -0.305054)
			(end -0.12065 -0.305054)
			(stroke
				(width 0.1)
				(type default)
			)
			(layer "F.Fab")
		)
		(fp_line
			(start 0.67945 -0.3048)
			(end 0.67945 0.3048)
			(stroke
				(width 0.1)
				(type default)
			)
			(layer "F.Fab")
		)
		(fp_line
			(start 0.12065 -0.3048)
			(end 0.67945 -0.3048)
			(stroke
				(width 0.1)
				(type default)
			)
			(layer "F.Fab")
		)
		(fp_line
			(start 0.12065 -0.2794)
			(end 0.12065 -0.3048)
			(stroke
				(width 0.1)
				(type default)
			)
			(layer "F.Fab")
		)
		(fp_line
			(start -0.12065 -0.2794)
			(end 0.12065 -0.2794)
			(stroke
				(width 0.1)
				(type default)
			)
			(layer "F.Fab")
		)
		(fp_line
			(start 0.120396 0.2794)
			(end -0.12065 0.2794)
			(stroke
				(width 0.1)
				(type default)
			)
			(layer "F.Fab")
		)
		(fp_line
			(start -0.12065 0.2794)
			(end -0.12065 0.3048)
			(stroke
				(width 0.1)
				(type default)
			)
			(layer "F.Fab")
		)
		(fp_line
			(start 0.67945 0.3048)
			(end 0.120396 0.3048)
			(stroke
				(width 0.1)
				(type default)
			)
			(layer "F.Fab")
		)
		(fp_line
			(start 0.120396 0.3048)
			(end 0.120396 0.2794)
			(stroke
				(width 0.1)
				(type default)
			)
			(layer "F.Fab")
		)
		(fp_line
			(start -0.12065 0.3048)
			(end -0.67945 0.3048)
			(stroke
				(width 0.1)
				(type default)
			)
			(layer "F.Fab")
		)
		(fp_line
			(start -0.67945 0.3048)
			(end -0.67945 -0.305054)
			(stroke
				(width 0.1)
				(type default)
			)
			(layer "F.Fab")
		)
		(pad "1" smd circle
			(at -0.40005 0 90)
			(size 0 0)
			(layers "F.Cu" "F.Mask" "F.Paste")
			(net "PVCCIN_CPU1")
		)
		(pad "2" smd circle
			(at 0.40005 0 90)
			(size 0 0)
			(layers "F.Cu" "F.Mask" "F.Paste")
			(net "GND")
		)
	)
	(footprint ""
		(layer "F.Cu")
		(at 139.855194 -408.517344 -90)
		(property "Reference" "C1528"
			(at 0 0 270)
			(layer "F.SilkS")
			(hide yes)
			(effects
				(font
					(size 1.27 1.27)
				)
			)
		)
		(property "Value" ""
			(at 0 0 270)
			(layer "F.Fab")
			(effects
				(font
					(size 1.27 1.27)
				)
			)
		)
		(duplicate_pad_numbers_are_jumpers no)
		(fp_line
			(start -0.299974 0.150114)
			(end -0.299974 -0.150114)
			(stroke
				(width 0.1)
				(type default)
			)
			(layer "F.Fab")
		)
		(fp_line
			(start 0.299974 0.150114)
			(end -0.299974 0.150114)
			(stroke
				(width 0.1)
				(type default)
			)
			(layer "F.Fab")
		)
		(fp_line
			(start -0.299974 -0.150114)
			(end 0.299974 -0.150114)
			(stroke
				(width 0.1)
				(type default)
			)
			(layer "F.Fab")
		)
		(fp_line
			(start 0.299974 -0.150114)
			(end 0.299974 0.150114)
			(stroke
				(width 0.1)
				(type default)
			)
			(layer "F.Fab")
		)
		(pad "1" smd rect
			(at -0.2667 0 270)
			(size 0.3048 0.381)
			(layers "F.Cu" "F.Mask" "F.Paste")
			(net "P5E_CPU1_PE3_TX_C_DN<9>")
		)
		(pad "2" smd rect
			(at 0.2667 0 270)
			(size 0.3048 0.381)
			(layers "F.Cu" "F.Mask" "F.Paste")
			(net "P5E_CPU1_PE3_TX_DN<9>")
		)
	)
	(footprint ""
		(layer "F.Cu")
		(at 463.343498 -43.221148 180)
		(property "Reference" "R4070"
			(at 0 0 180)
			(layer "F.SilkS")
			(hide yes)
			(effects
				(font
					(size 1.27 1.27)
				)
			)
		)
		(property "Value" ""
			(at 0 0 180)
			(layer "F.Fab")
			(effects
				(font
					(size 1.27 1.27)
				)
			)
		)
		(duplicate_pad_numbers_are_jumpers no)
		(fp_line
			(start 0.7874 0.4064)
			(end -0.7874 0.4064)
			(stroke
				(width 0.1524)
				(type default)
			)
			(layer "F.SilkS")
		)
		(fp_line
			(start 0.7874 -0.4064)
			(end 0.7874 0.4064)
			(stroke
				(width 0.1524)
				(type default)
			)
			(layer "F.SilkS")
		)
		(fp_line
			(start -0.7874 0.4064)
			(end -0.7874 -0.4064)
			(stroke
				(width 0.1524)
				(type default)
			)
			(layer "F.SilkS")
		)
		(fp_line
			(start -0.7874 -0.4064)
			(end 0.7874 -0.4064)
			(stroke
				(width 0.1524)
				(type default)
			)
			(layer "F.SilkS")
		)
		(fp_line
			(start 0.67945 0.3048)
			(end 0.120396 0.3048)
			(stroke
				(width 0.1)
				(type default)
			)
			(layer "F.Fab")
		)
		(fp_line
			(start 0.67945 -0.3048)
			(end 0.67945 0.3048)
			(stroke
				(width 0.1)
				(type default)
			)
			(layer "F.Fab")
		)
		(fp_line
			(start 0.12065 -0.2794)
			(end 0.12065 -0.3048)
			(stroke
				(width 0.1)
				(type default)
			)
			(layer "F.Fab")
		)
		(fp_line
			(start 0.12065 -0.3048)
			(end 0.67945 -0.3048)
			(stroke
				(width 0.1)
				(type default)
			)
			(layer "F.Fab")
		)
		(fp_line
			(start 0.120396 0.3048)
			(end 0.120396 0.2794)
			(stroke
				(width 0.1)
				(type default)
			)
			(layer "F.Fab")
		)
		(fp_line
			(start 0.120396 0.2794)
			(end -0.12065 0.2794)
			(stroke
				(width 0.1)
				(type default)
			)
			(layer "F.Fab")
		)
		(fp_line
			(start -0.12065 0.3048)
			(end -0.67945 0.3048)
			(stroke
				(width 0.1)
				(type default)
			)
			(layer "F.Fab")
		)
		(fp_line
			(start -0.12065 0.2794)
			(end -0.12065 0.3048)
			(stroke
				(width 0.1)
				(type default)
			)
			(layer "F.Fab")
		)
		(fp_line
			(start -0.12065 -0.2794)
			(end 0.12065 -0.2794)
			(stroke
				(width 0.1)
				(type default)
			)
			(layer "F.Fab")
		)
		(fp_line
			(start -0.12065 -0.305054)
			(end -0.12065 -0.2794)
			(stroke
				(width 0.1)
				(type default)
			)
			(layer "F.Fab")
		)
		(fp_line
			(start -0.67945 0.3048)
			(end -0.67945 -0.305054)
			(stroke
				(width 0.1)
				(type default)
			)
			(layer "F.Fab")
		)
		(fp_line
			(start -0.67945 -0.305054)
			(end -0.12065 -0.305054)
			(stroke
				(width 0.1)
				(type default)
			)
			(layer "F.Fab")
		)
		(pad "1" smd circle
			(at -0.40005 0 180)
			(size 0 0)
			(layers "F.Cu" "F.Mask" "F.Paste")
			(net "P12V_AUX")
		)
		(pad "2" smd circle
			(at 0.40005 0 180)
			(size 0 0)
			(layers "F.Cu" "F.Mask" "F.Paste")
			(net "P3V3_OCP_1_EN_G")
		)
	)
)
